# T6G (Grand Teton) — schematic netlist excerpt (pin names and nets, part order shuffled) for the footprints in the layout excerpt that follows; sources: Cadence DE-HDL packaged netlist, KiCad conversion of 04192023_DAF0TMB3IC0_F0TG_MB_C_brd_V02_OCP.brd

R753  Q_RES  10K 5% CHIP  pkg 0402LF  page 76 : A = GND ; B = PD_ESPI_CPU0_CLK2
C297  Q_CAP  10PF 50V 5% EMPTY  pkg 0402  page 210 : A = SVID_PVDDCR_CPU0_P1_SVC_R ; B = GND

(kicad_pcb
	(version 20260206)
	(generator "pcbnew")
	(generator_version "10.0")
	(general
		(thickness 1.6)
		(legacy_teardrops no)
	)
	(paper "A4")
	(title_block
		(title "04192023_DAF0TMB3IC0_F0TG_MB_C_brd_V02_OCP.brd")
		(comment 1 "Grand Teton / footprints 5996-5997 of 8354")
	)
	(layers
		(0 "F.Cu" signal "TOP")
		(4 "In1.Cu" signal "GND")
		(6 "In2.Cu" signal "IN1")
		(8 "In3.Cu" signal "GND1")
		(10 "In4.Cu" signal "IN2")
		(12 "In5.Cu" signal "GND2")
		(14 "In6.Cu" signal "IN3")
		(16 "In7.Cu" signal "GND3")
		(18 "In8.Cu" signal "VCC")
		(20 "In9.Cu" signal "VCC1")
		(22 "In10.Cu" signal "GND4")
		(24 "In11.Cu" signal "IN4")
		(26 "In12.Cu" signal "GND5")
		(28 "In13.Cu" signal "IN5")
		(30 "In14.Cu" signal "GND6")
		(32 "In15.Cu" signal "IN6")
		(34 "In16.Cu" signal "GND7")
		(2 "B.Cu" signal "BOTTOM")
		(9 "F.Adhes" user "F.Adhesive")
		(11 "B.Adhes" user "B.Adhesive")
		(13 "F.Paste" user "Package Geometry/Pastemask Top")
		(15 "B.Paste" user "Package Geometry/Pastemask Bottom")
		(5 "F.SilkS" user "Ref Des/Silkscreen Top")
		(7 "B.SilkS" user "Ref Des/Silkscreen Bottom")
		(1 "F.Mask" user "Board Geometry/Soldermask Top")
		(3 "B.Mask" user "Board Geometry/Soldermask Bottom")
		(17 "Dwgs.User" user "User.Drawings")
		(19 "Cmts.User" user "User.Comments")
		(21 "Eco1.User" user "User.Eco1")
		(23 "Eco2.User" user "User.Eco2")
		(25 "Edge.Cuts" user "Board Geometry/Outline")
		(27 "Margin" user)
		(31 "F.CrtYd" user "Package Geometry/Place Bound Top")
		(29 "B.CrtYd" user "Package Geometry/Place Bound Bottom")
		(35 "F.Fab" user "Ref Des/Assembly Top")
		(33 "B.Fab" user "Ref Des/Assembly Bottom")
	)
	(footprint ""
		(layer "B.Cu")
		(at 398.443958 -326.671432 180)
		(property "Reference" "R753"
			(at 0 0 0)
			(layer "B.SilkS")
			(hide yes)
			(effects
				(font
					(size 1.27 1.27)
				)
				(justify mirror)
			)
		)
		(property "Value" ""
			(at 0 0 0)
			(layer "B.Fab")
			(effects
				(font
					(size 1.27 1.27)
				)
				(justify mirror)
			)
		)
		(duplicate_pad_numbers_are_jumpers no)
		(fp_line
			(start 0.7874 0.4064)
			(end 0.7874 -0.4064)
			(stroke
				(width 0.1524)
				(type default)
			)
			(layer "B.SilkS")
		)
		(fp_line
			(start 0.7874 -0.4064)
			(end -0.7874 -0.4064)
			(stroke
				(width 0.1524)
				(type default)
			)
			(layer "B.SilkS")
		)
		(fp_line
			(start -0.7874 0.4064)
			(end 0.7874 0.4064)
			(stroke
				(width 0.1524)
				(type default)
			)
			(layer "B.SilkS")
		)
		(fp_line
			(start -0.7874 -0.4064)
			(end -0.7874 0.4064)
			(stroke
				(width 0.1524)
				(type default)
			)
			(layer "B.SilkS")
		)
		(fp_line
			(start 0.67945 0.3048)
			(end 0.67945 -0.305054)
			(stroke
				(width 0.1)
				(type default)
			)
			(layer "B.Fab")
		)
		(fp_line
			(start 0.67945 -0.305054)
			(end 0.12065 -0.305054)
			(stroke
				(width 0.1)
				(type default)
			)
			(layer "B.Fab")
		)
		(fp_line
			(start 0.12065 0.3048)
			(end 0.67945 0.3048)
			(stroke
				(width 0.1)
				(type default)
			)
			(layer "B.Fab")
		)
		(fp_line
			(start 0.12065 0.2794)
			(end 0.12065 0.3048)
			(stroke
				(width 0.1)
				(type default)
			)
			(layer "B.Fab")
		)
		(fp_line
			(start 0.12065 -0.2794)
			(end -0.12065 -0.2794)
			(stroke
				(width 0.1)
				(type default)
			)
			(layer "B.Fab")
		)
		(fp_line
			(start 0.12065 -0.305054)
			(end 0.12065 -0.2794)
			(stroke
				(width 0.1)
				(type default)
			)
			(layer "B.Fab")
		)
		(fp_line
			(start -0.120396 0.3048)
			(end -0.120396 0.2794)
			(stroke
				(width 0.1)
				(type default)
			)
			(layer "B.Fab")
		)
		(fp_line
			(start -0.120396 0.2794)
			(end 0.12065 0.2794)
			(stroke
				(width 0.1)
				(type default)
			)
			(layer "B.Fab")
		)
		(fp_line
			(start -0.12065 -0.2794)
			(end -0.12065 -0.3048)
			(stroke
				(width 0.1)
				(type default)
			)
			(layer "B.Fab")
		)
		(fp_line
			(start -0.12065 -0.3048)
			(end -0.67945 -0.3048)
			(stroke
				(width 0.1)
				(type default)
			)
			(layer "B.Fab")
		)
		(fp_line
			(start -0.67945 0.3048)
			(end -0.120396 0.3048)
			(stroke
				(width 0.1)
				(type default)
			)
			(layer "B.Fab")
		)
		(fp_line
			(start -0.67945 -0.3048)
			(end -0.67945 0.3048)
			(stroke
				(width 0.1)
				(type default)
			)
			(layer "B.Fab")
		)
		(pad "1" smd circle
			(at 0.40005 0)
			(size 0 0)
			(layers "B.Cu" "B.Mask" "B.Paste")
			(net "GND")
		)
		(pad "2" smd circle
			(at -0.40005 0)
			(size 0 0)
			(layers "B.Cu" "B.Mask" "B.Paste")
			(net "PD_ESPI_CPU0_CLK2")
		)
	)
	(footprint ""
		(layer "B.Cu")
		(at 85.852 -147.955)
		(property "Reference" "C297"
			(at 0 0 0)
			(layer "B.SilkS")
			(hide yes)
			(effects
				(font
					(size 1.27 1.27)
				)
				(justify mirror)
			)
		)
		(property "Value" ""
			(at 0 0 0)
			(layer "B.Fab")
			(effects
				(font
					(size 1.27 1.27)
				)
				(justify mirror)
			)
		)
		(duplicate_pad_numbers_are_jumpers no)
		(fp_line
			(start -0.7874 -0.4064)
			(end -0.7874 0.4064)
			(stroke
				(width 0.1524)
				(type default)
			)
			(layer "B.SilkS")
		)
		(fp_line
			(start -0.7874 0.4064)
			(end 0.7874 0.4064)
			(stroke
				(width 0.1524)
				(type default)
			)
			(layer "B.SilkS")
		)
		(fp_line
			(start 0.7874 -0.4064)
			(end -0.7874 -0.4064)
			(stroke
				(width 0.1524)
				(type default)
			)
			(layer "B.SilkS")
		)
		(fp_line
			(start 0.7874 0.4064)
			(end 0.7874 -0.4064)
			(stroke
				(width 0.1524)
				(type default)
			)
			(layer "B.SilkS")
		)
		(fp_line
			(start -0.67945 -0.3048)
			(end -0.67945 0.3048)
			(stroke
				(width 0.1)
				(type default)
			)
			(layer "B.Fab")
		)
		(fp_line
			(start -0.67945 0.3048)
			(end -0.120396 0.3048)
			(stroke
				(width 0.1)
				(type default)
			)
			(layer "B.Fab")
		)
		(fp_line
			(start -0.12065 -0.3048)
			(end -0.67945 -0.3048)
			(stroke
				(width 0.1)
				(type default)
			)
			(layer "B.Fab")
		)
		(fp_line
			(start -0.12065 -0.2794)
			(end -0.12065 -0.3048)
			(stroke
				(width 0.1)
				(type default)
			)
			(layer "B.Fab")
		)
		(fp_line
			(start -0.120396 0.2794)
			(end 0.12065 0.2794)
			(stroke
				(width 0.1)
				(type default)
			)
			(layer "B.Fab")
		)
		(fp_line
			(start -0.120396 0.3048)
			(end -0.120396 0.2794)
			(stroke
				(width 0.1)
				(type default)
			)
			(layer "B.Fab")
		)
		(fp_line
			(start 0.12065 -0.305054)
			(end 0.12065 -0.2794)
			(stroke
				(width 0.1)
				(type default)
			)
			(layer "B.Fab")
		)
		(fp_line
			(start 0.12065 -0.2794)
			(end -0.12065 -0.2794)
			(stroke
				(width 0.1)
				(type default)
			)
			(layer "B.Fab")
		)
		(fp_line
			(start 0.12065 0.2794)
			(end 0.12065 0.3048)
			(stroke
				(width 0.1)
				(type default)
			)
			(layer "B.Fab")
		)
		(fp_line
			(start 0.12065 0.3048)
			(end 0.67945 0.3048)
			(stroke
				(width 0.1)
				(type default)
			)
			(layer "B.Fab")
		)
		(fp_line
			(start 0.67945 -0.305054)
			(end 0.12065 -0.305054)
			(stroke
				(width 0.1)
				(type default)
			)
			(layer "B.Fab")
		)
		(fp_line
			(start 0.67945 0.3048)
			(end 0.67945 -0.305054)
			(stroke
				(width 0.1)
				(type default)
			)
			(layer "B.Fab")
		)
		(pad "1" smd circle
			(at 0.40005 0 180)
			(size 0 0)
			(layers "B.Cu" "B.Mask" "B.Paste")
			(net "SVID_PVDDCR_CPU0_P1_SVC_R")
		)
		(pad "2" smd circle
			(at -0.40005 0 180)
			(size 0 0)
			(layers "B.Cu" "B.Mask" "B.Paste")
			(net "GND")
		)
	)
)
